# T6G (Grand Teton) — schematic netlist excerpt (pin names and nets, part order shuffled) for the footprints in the layout excerpt that follows; sources: Cadence DE-HDL packaged netlist, KiCad conversion of 04192023_DAF0TMB3IC0_F0TG_MB_C_brd_V02_OCP.brd

R533  Q_RES  2.2K 5% CHIP  pkg 0402LF  page 54 : A = CPU1_BP2 ; B = PVDD18_S5_P1
PC2080  Q_CAP  22UF 16V 20% X6S  pkg C0805  page 134 : A = P12V_OCP_SFF ; B = GND
C2246  Q_CAP  22UF 4V 20% X6S  pkg C0402  page 69 : A = PVDDCR_CPU1_P0 ; B = GND

(kicad_pcb
	(version 20260206)
	(generator "pcbnew")
	(generator_version "10.0")
	(general
		(thickness 1.6)
		(legacy_teardrops no)
	)
	(paper "A4")
	(title_block
		(title "04192023_DAF0TMB3IC0_F0TG_MB_C_brd_V02_OCP.brd")
		(comment 1 "Grand Teton / footprints 8182-8184 of 8354")
	)
	(layers
		(0 "F.Cu" signal "TOP")
		(4 "In1.Cu" signal "GND")
		(6 "In2.Cu" signal "IN1")
		(8 "In3.Cu" signal "GND1")
		(10 "In4.Cu" signal "IN2")
		(12 "In5.Cu" signal "GND2")
		(14 "In6.Cu" signal "IN3")
		(16 "In7.Cu" signal "GND3")
		(18 "In8.Cu" signal "VCC")
		(20 "In9.Cu" signal "VCC1")
		(22 "In10.Cu" signal "GND4")
		(24 "In11.Cu" signal "IN4")
		(26 "In12.Cu" signal "GND5")
		(28 "In13.Cu" signal "IN5")
		(30 "In14.Cu" signal "GND6")
		(32 "In15.Cu" signal "IN6")
		(34 "In16.Cu" signal "GND7")
		(2 "B.Cu" signal "BOTTOM")
		(9 "F.Adhes" user "F.Adhesive")
		(11 "B.Adhes" user "B.Adhesive")
		(13 "F.Paste" user "Package Geometry/Pastemask Top")
		(15 "B.Paste" user "Package Geometry/Pastemask Bottom")
		(5 "F.SilkS" user "Ref Des/Silkscreen Top")
		(7 "B.SilkS" user "Ref Des/Silkscreen Bottom")
		(1 "F.Mask" user "Board Geometry/Soldermask Top")
		(3 "B.Mask" user "Board Geometry/Soldermask Bottom")
		(17 "Dwgs.User" user "User.Drawings")
		(19 "Cmts.User" user "User.Comments")
		(21 "Eco1.User" user "User.Eco1")
		(23 "Eco2.User" user "User.Eco2")
		(25 "Edge.Cuts" user "Board Geometry/Outline")
		(27 "Margin" user)
		(31 "F.CrtYd" user "Package Geometry/Place Bound Top")
		(29 "B.CrtYd" user "Package Geometry/Place Bound Bottom")
		(35 "F.Fab" user "Ref Des/Assembly Top")
		(33 "B.Fab" user "Ref Des/Assembly Bottom")
	)
	(footprint ""
		(layer "B.Cu")
		(at 94.059502 -205.14945 90)
		(property "Reference" "R533"
			(at 0 0 90)
			(layer "B.SilkS")
			(hide yes)
			(effects
				(font
					(size 1.27 1.27)
				)
				(justify mirror)
			)
		)
		(property "Value" ""
			(at 0 0 90)
			(layer "B.Fab")
			(effects
				(font
					(size 1.27 1.27)
				)
				(justify mirror)
			)
		)
		(duplicate_pad_numbers_are_jumpers no)
		(fp_line
			(start 0.7874 -0.4064)
			(end -0.7874 -0.4064)
			(stroke
				(width 0.1524)
				(type default)
			)
			(layer "B.SilkS")
		)
		(fp_line
			(start -0.7874 -0.4064)
			(end -0.7874 0.4064)
			(stroke
				(width 0.1524)
				(type default)
			)
			(layer "B.SilkS")
		)
		(fp_line
			(start 0.7874 0.4064)
			(end 0.7874 -0.4064)
			(stroke
				(width 0.1524)
				(type default)
			)
			(layer "B.SilkS")
		)
		(fp_line
			(start -0.7874 0.4064)
			(end 0.7874 0.4064)
			(stroke
				(width 0.1524)
				(type default)
			)
			(layer "B.SilkS")
		)
		(fp_line
			(start 0.67945 -0.305054)
			(end 0.12065 -0.305054)
			(stroke
				(width 0.1)
				(type default)
			)
			(layer "B.Fab")
		)
		(fp_line
			(start 0.12065 -0.305054)
			(end 0.12065 -0.2794)
			(stroke
				(width 0.1)
				(type default)
			)
			(layer "B.Fab")
		)
		(fp_line
			(start -0.12065 -0.3048)
			(end -0.67945 -0.3048)
			(stroke
				(width 0.1)
				(type default)
			)
			(layer "B.Fab")
		)
		(fp_line
			(start -0.67945 -0.3048)
			(end -0.67945 0.3048)
			(stroke
				(width 0.1)
				(type default)
			)
			(layer "B.Fab")
		)
		(fp_line
			(start 0.12065 -0.2794)
			(end -0.12065 -0.2794)
			(stroke
				(width 0.1)
				(type default)
			)
			(layer "B.Fab")
		)
		(fp_line
			(start -0.12065 -0.2794)
			(end -0.12065 -0.3048)
			(stroke
				(width 0.1)
				(type default)
			)
			(layer "B.Fab")
		)
		(fp_line
			(start 0.12065 0.2794)
			(end 0.12065 0.3048)
			(stroke
				(width 0.1)
				(type default)
			)
			(layer "B.Fab")
		)
		(fp_line
			(start -0.120396 0.2794)
			(end 0.12065 0.2794)
			(stroke
				(width 0.1)
				(type default)
			)
			(layer "B.Fab")
		)
		(fp_line
			(start 0.67945 0.3048)
			(end 0.67945 -0.305054)
			(stroke
				(width 0.1)
				(type default)
			)
			(layer "B.Fab")
		)
		(fp_line
			(start 0.12065 0.3048)
			(end 0.67945 0.3048)
			(stroke
				(width 0.1)
				(type default)
			)
			(layer "B.Fab")
		)
		(fp_line
			(start -0.120396 0.3048)
			(end -0.120396 0.2794)
			(stroke
				(width 0.1)
				(type default)
			)
			(layer "B.Fab")
		)
		(fp_line
			(start -0.67945 0.3048)
			(end -0.120396 0.3048)
			(stroke
				(width 0.1)
				(type default)
			)
			(layer "B.Fab")
		)
		(pad "1" smd circle
			(at 0.40005 0 270)
			(size 0 0)
			(layers "B.Cu" "B.Mask" "B.Paste")
			(net "CPU1_BP2")
		)
		(pad "2" smd circle
			(at -0.40005 0 270)
			(size 0 0)
			(layers "B.Cu" "B.Mask" "B.Paste")
			(net "PVDD18_S5_P1")
		)
	)
	(footprint ""
		(layer "B.Cu")
		(at 373.424958 -268.855952 60)
		(property "Reference" "C2246"
			(at 0 0 60)
			(layer "B.SilkS")
			(hide yes)
			(effects
				(font
					(size 1.27 1.27)
				)
				(justify mirror)
			)
		)
		(property "Value" ""
			(at 0 0 60)
			(layer "B.Fab")
			(effects
				(font
					(size 1.27 1.27)
				)
				(justify mirror)
			)
		)
		(duplicate_pad_numbers_are_jumpers no)
		(fp_line
			(start -0.787516 -0.406438)
			(end -0.787425 0.40652)
			(stroke
				(width 0.1524)
				(type default)
			)
			(layer "B.SilkS")
		)
		(fp_line
			(start -0.787425 0.40652)
			(end 0.787516 0.406438)
			(stroke
				(width 0.1524)
				(type default)
			)
			(layer "B.SilkS")
		)
		(fp_line
			(start 0.787425 -0.40652)
			(end -0.787516 -0.406438)
			(stroke
				(width 0.1524)
				(type default)
			)
			(layer "B.SilkS")
		)
		(fp_line
			(start 0.787516 0.406438)
			(end 0.787425 -0.40652)
			(stroke
				(width 0.1524)
				(type default)
			)
			(layer "B.SilkS")
		)
		(fp_line
			(start -0.679568 -0.304811)
			(end -0.6795 0.304908)
			(stroke
				(width 0.1)
				(type default)
			)
			(layer "B.Fab")
		)
		(fp_line
			(start -0.120605 -0.304905)
			(end -0.679568 -0.304811)
			(stroke
				(width 0.1)
				(type default)
			)
			(layer "B.Fab")
		)
		(fp_line
			(start -0.120554 -0.279418)
			(end -0.120605 -0.304905)
			(stroke
				(width 0.1)
				(type default)
			)
			(layer "B.Fab")
		)
		(fp_line
			(start 0.120629 -0.30516)
			(end 0.120587 -0.279326)
			(stroke
				(width 0.1)
				(type default)
			)
			(layer "B.Fab")
		)
		(fp_line
			(start 0.120587 -0.279326)
			(end -0.120554 -0.279418)
			(stroke
				(width 0.1)
				(type default)
			)
			(layer "B.Fab")
		)
		(fp_line
			(start -0.6795 0.304908)
			(end -0.120316 0.304686)
			(stroke
				(width 0.1)
				(type default)
			)
			(layer "B.Fab")
		)
		(fp_line
			(start 0.679373 -0.305128)
			(end 0.120629 -0.30516)
			(stroke
				(width 0.1)
				(type default)
			)
			(layer "B.Fab")
		)
		(fp_line
			(start -0.12024 0.279419)
			(end 0.120554 0.279418)
			(stroke
				(width 0.1)
				(type default)
			)
			(layer "B.Fab")
		)
		(fp_line
			(start -0.120316 0.304686)
			(end -0.12024 0.279419)
			(stroke
				(width 0.1)
				(type default)
			)
			(layer "B.Fab")
		)
		(fp_line
			(start 0.120554 0.279418)
			(end 0.120605 0.304905)
			(stroke
				(width 0.1)
				(type default)
			)
			(layer "B.Fab")
		)
		(fp_line
			(start 0.120605 0.304905)
			(end 0.679568 0.304811)
			(stroke
				(width 0.1)
				(type default)
			)
			(layer "B.Fab")
		)
		(fp_line
			(start 0.679568 0.304811)
			(end 0.679373 -0.305128)
			(stroke
				(width 0.1)
				(type default)
			)
			(layer "B.Fab")
		)
		(pad "1" smd circle
			(at 0.40005 0 240)
			(size 0 0)
			(layers "B.Cu" "B.Mask" "B.Paste")
			(net "PVDDCR_CPU1_P0")
		)
		(pad "2" smd circle
			(at -0.40005 0 240)
			(size 0 0)
			(layers "B.Cu" "B.Mask" "B.Paste")
			(net "GND")
		)
	)
	(footprint ""
		(layer "B.Cu")
		(at 440.153806 -21.932392)
		(property "Reference" "PC2080"
			(at 0 0 0)
			(layer "B.SilkS")
			(hide yes)
			(effects
				(font
					(size 1.27 1.27)
				)
				(justify mirror)
			)
		)
		(property "Value" ""
			(at 0 0 0)
			(layer "B.Fab")
			(effects
				(font
					(size 1.27 1.27)
				)
				(justify mirror)
			)
		)
		(duplicate_pad_numbers_are_jumpers no)
		(fp_line
			(start -1.524 -0.762)
			(end -1.524 0.762)
			(stroke
				(width 0.1524)
				(type default)
			)
			(layer "B.SilkS")
		)
		(fp_line
			(start -1.524 0.762)
			(end 1.524 0.762)
			(stroke
				(width 0.1524)
				(type default)
			)
			(layer "B.SilkS")
		)
		(fp_line
			(start 1.524 -0.762)
			(end -1.524 -0.762)
			(stroke
				(width 0.1524)
				(type default)
			)
			(layer "B.SilkS")
		)
		(fp_line
			(start 1.524 0.762)
			(end 1.524 -0.762)
			(stroke
				(width 0.1524)
				(type default)
			)
			(layer "B.SilkS")
		)
		(fp_line
			(start -1.1049 -0.724916)
			(end 1.1049 -0.724916)
			(stroke
				(width 0.1)
				(type default)
			)
			(layer "B.Fab")
		)
		(fp_line
			(start -1.1049 0.724916)
			(end -1.1049 -0.724916)
			(stroke
				(width 0.1)
				(type default)
			)
			(layer "B.Fab")
		)
		(fp_line
			(start 1.1049 -0.724916)
			(end 1.1049 0.724916)
			(stroke
				(width 0.1)
				(type default)
			)
			(layer "B.Fab")
		)
		(fp_line
			(start 1.1049 0.724916)
			(end -1.1049 0.724916)
			(stroke
				(width 0.1)
				(type default)
			)
			(layer "B.Fab")
		)
		(pad "1" smd rect
			(at 0.889 0)
			(size 1.016 1.27)
			(layers "B.Cu" "B.Mask" "B.Paste")
			(net "P12V_OCP_SFF")
		)
		(pad "2" smd rect
			(at -0.889 0)
			(size 1.016 1.27)
			(layers "B.Cu" "B.Mask" "B.Paste")
			(net "GND")
		)
	)
)
